(kicad_pcb
	(version 20260206)
	(generator "pcbnew")
	(generator_version "10.0")
	(general
		(thickness 1.6)
		(legacy_teardrops no)
	)
	(paper "A4")
	(title_block
		(title "01162023_DA0F0TEBIF0_F0T_Expander_BD_F_brd_V02_OCP.brd")
		(comment 1 "Grand Teton / footprints 5065-5069 of 9728")
	)
	(layers
		(0 "F.Cu" signal "TOP")
		(4 "In1.Cu" signal "GND")
		(6 "In2.Cu" signal "VCC")
		(8 "In3.Cu" signal "VCC1")
		(10 "In4.Cu" signal "GND1")
		(12 "In5.Cu" signal "IN1")
		(14 "In6.Cu" signal "GND2")
		(16 "In7.Cu" signal "IN2")
		(18 "In8.Cu" signal "GND3")
		(20 "In9.Cu" signal "IN3")
		(22 "In10.Cu" signal "GND4")
		(24 "In11.Cu" signal "IN4")
		(26 "In12.Cu" signal "GND5")
		(28 "In13.Cu" signal "IN5")
		(30 "In14.Cu" signal "GND6")
		(32 "In15.Cu" signal "IN6")
		(34 "In16.Cu" signal "GND7")
		(2 "B.Cu" signal "BOTTOM")
		(9 "F.Adhes" user "F.Adhesive")
		(11 "B.Adhes" user "B.Adhesive")
		(13 "F.Paste" user "Package Geometry/Pastemask Top")
		(15 "B.Paste" user "Package Geometry/Pastemask Bottom")
		(5 "F.SilkS" user "Ref Des/Silkscreen Top")
		(7 "B.SilkS" user "Ref Des/Silkscreen Bottom")
		(1 "F.Mask" user "Board Geometry/Soldermask Top")
		(3 "B.Mask" user "Board Geometry/Soldermask Bottom")
		(17 "Dwgs.User" user "User.Drawings")
		(19 "Cmts.User" user "User.Comments")
		(21 "Eco1.User" user "User.Eco1")
		(23 "Eco2.User" user "User.Eco2")
		(25 "Edge.Cuts" user "Board Geometry/Outline")
		(27 "Margin" user)
		(31 "F.CrtYd" user "Package Geometry/Place Bound Top")
		(29 "B.CrtYd" user "Package Geometry/Place Bound Bottom")
		(35 "F.Fab" user "Ref Des/Assembly Top")
		(33 "B.Fab" user "Ref Des/Assembly Bottom")
	)
	(footprint ""
		(layer "F.Cu")
		(at 336.931 -234.061 -90)
		(property "Reference" "R3546"
			(at 0 0 270)
			(layer "F.SilkS")
			(hide yes)
			(effects
				(font
					(size 1.27 1.27)
				)
			)
		)
		(property "Value" ""
			(at 0 0 270)
			(layer "F.Fab")
			(effects
				(font
					(size 1.27 1.27)
				)
			)
		)
		(duplicate_pad_numbers_are_jumpers no)
		(fp_line
			(start -0.7874 0.4064)
			(end -0.7874 -0.4064)
			(stroke
				(width 0.1524)
				(type default)
			)
			(layer "F.SilkS")
		)
		(fp_line
			(start 0.7874 0.4064)
			(end -0.7874 0.4064)
			(stroke
				(width 0.1524)
				(type default)
			)
			(layer "F.SilkS")
		)
		(fp_line
			(start -0.7874 -0.4064)
			(end 0.7874 -0.4064)
			(stroke
				(width 0.1524)
				(type default)
			)
			(layer "F.SilkS")
		)
		(fp_line
			(start 0.7874 -0.4064)
			(end 0.7874 0.4064)
			(stroke
				(width 0.1524)
				(type default)
			)
			(layer "F.SilkS")
		)
		(fp_line
			(start -0.67945 0.3048)
			(end -0.67945 -0.305054)
			(stroke
				(width 0.1)
				(type default)
			)
			(layer "F.Fab")
		)
		(fp_line
			(start -0.12065 0.3048)
			(end -0.67945 0.3048)
			(stroke
				(width 0.1)
				(type default)
			)
			(layer "F.Fab")
		)
		(fp_line
			(start 0.120396 0.3048)
			(end 0.120396 0.2794)
			(stroke
				(width 0.1)
				(type default)
			)
			(layer "F.Fab")
		)
		(fp_line
			(start 0.67945 0.3048)
			(end 0.120396 0.3048)
			(stroke
				(width 0.1)
				(type default)
			)
			(layer "F.Fab")
		)
		(fp_line
			(start -0.12065 0.2794)
			(end -0.12065 0.3048)
			(stroke
				(width 0.1)
				(type default)
			)
			(layer "F.Fab")
		)
		(fp_line
			(start 0.120396 0.2794)
			(end -0.12065 0.2794)
			(stroke
				(width 0.1)
				(type default)
			)
			(layer "F.Fab")
		)
		(fp_line
			(start -0.12065 -0.2794)
			(end 0.12065 -0.2794)
			(stroke
				(width 0.1)
				(type default)
			)
			(layer "F.Fab")
		)
		(fp_line
			(start 0.12065 -0.2794)
			(end 0.12065 -0.3048)
			(stroke
				(width 0.1)
				(type default)
			)
			(layer "F.Fab")
		)
		(fp_line
			(start 0.12065 -0.3048)
			(end 0.67945 -0.3048)
			(stroke
				(width 0.1)
				(type default)
			)
			(layer "F.Fab")
		)
		(fp_line
			(start 0.67945 -0.3048)
			(end 0.67945 0.3048)
			(stroke
				(width 0.1)
				(type default)
			)
			(layer "F.Fab")
		)
		(fp_line
			(start -0.67945 -0.305054)
			(end -0.12065 -0.305054)
			(stroke
				(width 0.1)
				(type default)
			)
			(layer "F.Fab")
		)
		(fp_line
			(start -0.12065 -0.305054)
			(end -0.12065 -0.2794)
			(stroke
				(width 0.1)
				(type default)
			)
			(layer "F.Fab")
		)
		(pad "1" smd circle
			(at -0.40005 0 270)
			(size 0 0)
			(layers "F.Cu" "F.Mask" "F.Paste")
			(net "SYS_PWR_READY_R_N")
		)
		(pad "2" smd circle
			(at 0.40005 0 270)
			(size 0 0)
			(layers "F.Cu" "F.Mask" "F.Paste")
			(net "SYS_PWR_READY_N")
		)
	)
	(footprint ""
		(layer "F.Cu")
		(at 260.540246 -77.279754 -90)
		(property "Reference" "R1079"
			(at 0 0 270)
			(layer "F.SilkS")
			(hide yes)
			(effects
				(font
					(size 1.27 1.27)
				)
			)
		)
		(property "Value" ""
			(at 0 0 270)
			(layer "F.Fab")
			(effects
				(font
					(size 1.27 1.27)
				)
			)
		)
		(duplicate_pad_numbers_are_jumpers no)
		(fp_line
			(start -0.7874 0.4064)
			(end -0.7874 -0.4064)
			(stroke
				(width 0.1524)
				(type default)
			)
			(layer "F.SilkS")
		)
		(fp_line
			(start 0.7874 0.4064)
			(end -0.7874 0.4064)
			(stroke
				(width 0.1524)
				(type default)
			)
			(layer "F.SilkS")
		)
		(fp_line
			(start -0.7874 -0.4064)
			(end 0.7874 -0.4064)
			(stroke
				(width 0.1524)
				(type default)
			)
			(layer "F.SilkS")
		)
		(fp_line
			(start 0.7874 -0.4064)
			(end 0.7874 0.4064)
			(stroke
				(width 0.1524)
				(type default)
			)
			(layer "F.SilkS")
		)
		(fp_line
			(start -0.67945 0.3048)
			(end -0.67945 -0.305054)
			(stroke
				(width 0.1)
				(type default)
			)
			(layer "F.Fab")
		)
		(fp_line
			(start -0.12065 0.3048)
			(end -0.67945 0.3048)
			(stroke
				(width 0.1)
				(type default)
			)
			(layer "F.Fab")
		)
		(fp_line
			(start 0.120396 0.3048)
			(end 0.120396 0.2794)
			(stroke
				(width 0.1)
				(type default)
			)
			(layer "F.Fab")
		)
		(fp_line
			(start 0.67945 0.3048)
			(end 0.120396 0.3048)
			(stroke
				(width 0.1)
				(type default)
			)
			(layer "F.Fab")
		)
		(fp_line
			(start -0.12065 0.2794)
			(end -0.12065 0.3048)
			(stroke
				(width 0.1)
				(type default)
			)
			(layer "F.Fab")
		)
		(fp_line
			(start 0.120396 0.2794)
			(end -0.12065 0.2794)
			(stroke
				(width 0.1)
				(type default)
			)
			(layer "F.Fab")
		)
		(fp_line
			(start -0.12065 -0.2794)
			(end 0.12065 -0.2794)
			(stroke
				(width 0.1)
				(type default)
			)
			(layer "F.Fab")
		)
		(fp_line
			(start 0.12065 -0.2794)
			(end 0.12065 -0.3048)
			(stroke
				(width 0.1)
				(type default)
			)
			(layer "F.Fab")
		)
		(fp_line
			(start 0.12065 -0.3048)
			(end 0.67945 -0.3048)
			(stroke
				(width 0.1)
				(type default)
			)
			(layer "F.Fab")
		)
		(fp_line
			(start 0.67945 -0.3048)
			(end 0.67945 0.3048)
			(stroke
				(width 0.1)
				(type default)
			)
			(layer "F.Fab")
		)
		(fp_line
			(start -0.67945 -0.305054)
			(end -0.12065 -0.305054)
			(stroke
				(width 0.1)
				(type default)
			)
			(layer "F.Fab")
		)
		(fp_line
			(start -0.12065 -0.305054)
			(end -0.12065 -0.2794)
			(stroke
				(width 0.1)
				(type default)
			)
			(layer "F.Fab")
		)
		(pad "1" smd circle
			(at -0.40005 0 270)
			(size 0 0)
			(layers "F.Cu" "F.Mask" "F.Paste")
			(net "CLK_GEN_CK440_OE4_N")
		)
		(pad "2" smd circle
			(at 0.40005 0 270)
			(size 0 0)
			(layers "F.Cu" "F.Mask" "F.Paste")
			(net "P3V3")
		)
	)
	(footprint ""
		(layer "F.Cu")
		(at 240.35258 -223.066864 180)
		(property "Reference" "R4855"
			(at 0 0 180)
			(layer "F.SilkS")
			(hide yes)
			(effects
				(font
					(size 1.27 1.27)
				)
			)
		)
		(property "Value" ""
			(at 0 0 180)
			(layer "F.Fab")
			(effects
				(font
					(size 1.27 1.27)
				)
			)
		)
		(duplicate_pad_numbers_are_jumpers no)
		(fp_line
			(start 0.7874 0.4064)
			(end -0.7874 0.4064)
			(stroke
				(width 0.1524)
				(type default)
			)
			(layer "F.SilkS")
		)
		(fp_line
			(start 0.7874 -0.4064)
			(end 0.7874 0.4064)
			(stroke
				(width 0.1524)
				(type default)
			)
			(layer "F.SilkS")
		)
		(fp_line
			(start -0.7874 0.4064)
			(end -0.7874 -0.4064)
			(stroke
				(width 0.1524)
				(type default)
			)
			(layer "F.SilkS")
		)
		(fp_line
			(start -0.7874 -0.4064)
			(end 0.7874 -0.4064)
			(stroke
				(width 0.1524)
				(type default)
			)
			(layer "F.SilkS")
		)
		(fp_line
			(start 0.67945 0.3048)
			(end 0.120396 0.3048)
			(stroke
				(width 0.1)
				(type default)
			)
			(layer "F.Fab")
		)
		(fp_line
			(start 0.67945 -0.3048)
			(end 0.67945 0.3048)
			(stroke
				(width 0.1)
				(type default)
			)
			(layer "F.Fab")
		)
		(fp_line
			(start 0.12065 -0.2794)
			(end 0.12065 -0.3048)
			(stroke
				(width 0.1)
				(type default)
			)
			(layer "F.Fab")
		)
		(fp_line
			(start 0.12065 -0.3048)
			(end 0.67945 -0.3048)
			(stroke
				(width 0.1)
				(type default)
			)
			(layer "F.Fab")
		)
		(fp_line
			(start 0.120396 0.3048)
			(end 0.120396 0.2794)
			(stroke
				(width 0.1)
				(type default)
			)
			(layer "F.Fab")
		)
		(fp_line
			(start 0.120396 0.2794)
			(end -0.12065 0.2794)
			(stroke
				(width 0.1)
				(type default)
			)
			(layer "F.Fab")
		)
		(fp_line
			(start -0.12065 0.3048)
			(end -0.67945 0.3048)
			(stroke
				(width 0.1)
				(type default)
			)
			(layer "F.Fab")
		)
		(fp_line
			(start -0.12065 0.2794)
			(end -0.12065 0.3048)
			(stroke
				(width 0.1)
				(type default)
			)
			(layer "F.Fab")
		)
		(fp_line
			(start -0.12065 -0.2794)
			(end 0.12065 -0.2794)
			(stroke
				(width 0.1)
				(type default)
			)
			(layer "F.Fab")
		)
		(fp_line
			(start -0.12065 -0.305054)
			(end -0.12065 -0.2794)
			(stroke
				(width 0.1)
				(type default)
			)
			(layer "F.Fab")
		)
		(fp_line
			(start -0.67945 0.3048)
			(end -0.67945 -0.305054)
			(stroke
				(width 0.1)
				(type default)
			)
			(layer "F.Fab")
		)
		(fp_line
			(start -0.67945 -0.305054)
			(end -0.12065 -0.305054)
			(stroke
				(width 0.1)
				(type default)
			)
			(layer "F.Fab")
		)
		(pad "1" smd circle
			(at -0.40005 0 180)
			(size 0 0)
			(layers "F.Cu" "F.Mask" "F.Paste")
			(net "P1V2_AUX")
		)
		(pad "2" smd circle
			(at 0.40005 0 180)
			(size 0 0)
			(layers "F.Cu" "F.Mask" "F.Paste")
			(net "P1V2_BIC_ADCVREFREXT1")
		)
	)
	(footprint ""
		(layer "F.Cu")
		(at 113.970816 -126.654814)
		(property "Reference" "PU21"
			(at -0.827024 2.31521 0)
			(unlocked yes)
			(layer "F.SilkS")
			(effects
				(font
					(size 0.7874 0.5842)
					(thickness 0.1524)
				)
				(justify left)
			)
		)
		(property "Value" ""
			(at 0 0 0)
			(layer "F.Fab")
			(effects
				(font
					(size 1.27 1.27)
				)
			)
		)
		(duplicate_pad_numbers_are_jumpers no)
		(fp_line
			(start -1.943608 -1.549908)
			(end 1.943608 -1.549908)
			(stroke
				(width 0.1524)
				(type default)
			)
			(layer "F.SilkS")
		)
		(fp_line
			(start -1.943608 1.549908)
			(end -1.943608 -1.549908)
			(stroke
				(width 0.1524)
				(type default)
			)
			(layer "F.SilkS")
		)
		(fp_line
			(start 1.943608 -1.549908)
			(end 1.943608 1.549908)
			(stroke
				(width 0.1524)
				(type default)
			)
			(layer "F.SilkS")
		)
		(fp_line
			(start 1.943608 1.549908)
			(end -1.943608 1.549908)
			(stroke
				(width 0.1524)
				(type default)
			)
			(layer "F.SilkS")
		)
		(fp_poly
			(pts
				(xy -2.019808 -1.549908) (xy -1.257808 -1.549908) (xy -1.257808 -1.880108) (xy -2.019808 -1.880108)
			)
			(stroke
				(width 0)
				(type default)
			)
			(fill yes)
			(layer "F.SilkS")
		)
		(fp_line
			(start -1.549908 -1.549908)
			(end 1.549908 -1.549908)
			(stroke
				(width 0.1)
				(type default)
			)
			(layer "F.Fab")
		)
		(fp_line
			(start -1.549908 1.549908)
			(end -1.549908 -1.549908)
			(stroke
				(width 0.1)
				(type default)
			)
			(layer "F.Fab")
		)
		(fp_line
			(start 1.549908 -1.549908)
			(end 1.549908 1.549908)
			(stroke
				(width 0.1)
				(type default)
			)
			(layer "F.Fab")
		)
		(fp_line
			(start 1.549908 1.549908)
			(end -1.549908 1.549908)
			(stroke
				(width 0.1)
				(type default)
			)
			(layer "F.Fab")
		)
		(fp_poly
			(pts
				(xy -2.019808 -1.549908) (xy -1.257808 -1.549908) (xy -1.257808 -1.880108) (xy -2.019808 -1.880108)
			)
			(stroke
				(width 0)
				(type default)
			)
			(fill yes)
			(layer "F.Fab")
		)
		(pad "1" smd rect
			(at -1.500124 -1.249934 270)
			(size 0.2794 0.6096)
			(layers "F.Cu" "F.Mask" "F.Paste")
			(net "P3V3")
		)
		(pad "2" smd rect
			(at -1.500124 -0.750062 270)
			(size 0.2794 0.6096)
			(layers "F.Cu" "F.Mask" "F.Paste")
			(net "P3V3")
		)
		(pad "3" smd rect
			(at -1.500124 -0.249936 270)
			(size 0.2794 0.6096)
			(layers "F.Cu" "F.Mask" "F.Paste")
			(net "P3V3")
		)
		(pad "4" smd rect
			(at -1.500124 0.249936 270)
			(size 0.2794 0.6096)
			(layers "F.Cu" "F.Mask" "F.Paste")
			(net "P3V3")
		)
		(pad "5" smd rect
			(at -1.500124 0.750062 270)
			(size 0.2794 0.6096)
			(layers "F.Cu" "F.Mask" "F.Paste")
			(net "P3V3")
		)
		(pad "6" smd rect
			(at -1.500124 1.249934 270)
			(size 0.2794 0.6096)
			(layers "F.Cu" "F.Mask" "F.Paste")
			(net "GND")
		)
		(pad "7" smd rect
			(at 1.500124 1.249934 270)
			(size 0.2794 0.6096)
			(layers "F.Cu" "F.Mask" "F.Paste")
			(net "P3V3_SS")
		)
		(pad "8" smd rect
			(at 1.500124 0.750062 270)
			(size 0.2794 0.6096)
			(layers "F.Cu" "F.Mask" "F.Paste")
			(net "PWRGD_P3V3")
		)
		(pad "9" smd rect
			(at 1.500124 0.249936 270)
			(size 0.2794 0.6096)
			(layers "F.Cu" "F.Mask" "F.Paste")
			(net "P3V3_OCP")
		)
		(pad "10" smd rect
			(at 1.500124 -0.249936 270)
			(size 0.2794 0.6096)
			(layers "F.Cu" "F.Mask" "F.Paste")
			(net "P5V_AUX")
		)
		(pad "11" smd rect
			(at 1.500124 -0.750062 270)
			(size 0.2794 0.6096)
			(layers "F.Cu" "F.Mask" "F.Paste")
			(net "PWR_EN_P3V3_R")
		)
		(pad "12" smd rect
			(at 1.500124 -1.249934 270)
			(size 0.2794 0.6096)
			(layers "F.Cu" "F.Mask" "F.Paste")
			(net "P3V3_AUX")
		)
		(pad "13" smd rect
			(at 0 0)
			(size 1.9812 2.7178)
			(layers "F.Cu" "F.Mask" "F.Paste")
			(net "P3V3_AUX")
		)
		(zone
			(layer "F.Cu")
			(hatch none 0.5)
			(connect_pads
				(clearance 0)
			)
			(min_thickness 0.25)
			(keepout
				(tracks not_allowed)
				(vias allowed)
				(pads allowed)
				(copperpour not_allowed)
				(footprints allowed)
			)
			(placement
				(enabled no)
				(sheetname "")
			)
			(fill
				(thermal_gap 0.5)
				(thermal_bridge_width 0.5)
				(island_removal_mode 0)
			)
			(polygon
				(pts
					(xy 115.113816 -128.204214) (xy 115.113816 -128.077214) (xy 115.113816 -125.105414) (xy 115.113816 -125.104906)
					(xy 112.827816 -125.104906) (xy 112.827816 -125.105414) (xy 112.827816 -125.232414) (xy 112.827816 -126.654814)
					(xy 112.929416 -126.654814) (xy 112.929416 -125.232414) (xy 115.012216 -125.232414) (xy 115.012216 -128.077214)
					(xy 112.929416 -128.077214) (xy 112.929416 -126.680214) (xy 112.827816 -126.680214) (xy 112.827816 -128.077214)
					(xy 112.827816 -128.204214) (xy 112.827816 -128.204722) (xy 115.113816 -128.204722)
				)
			)
		)
	)
	(footprint ""
		(layer "F.Cu")
		(at 129.403856 -170.599862 90)
		(property "Reference" "R1091"
			(at 0 0 90)
			(layer "F.SilkS")
			(hide yes)
			(effects
				(font
					(size 1.27 1.27)
				)
			)
		)
		(property "Value" ""
			(at 0 0 90)
			(layer "F.Fab")
			(effects
				(font
					(size 1.27 1.27)
				)
			)
		)
		(duplicate_pad_numbers_are_jumpers no)
		(fp_line
			(start 0.7874 0.4064)
			(end -0.7874 0.4064)
			(stroke
				(width 0.1524)
				(type default)
			)
			(layer "F.SilkS")
		)
		(fp_line
			(start -0.12065 -0.305054)
			(end -0.12065 -0.2794)
			(stroke
				(width 0.1)
				(type default)
			)
			(layer "F.Fab")
		)
		(fp_line
			(start -0.67945 -0.305054)
			(end -0.12065 -0.305054)
			(stroke
				(width 0.1)
				(type default)
			)
			(layer "F.Fab")
		)
		(fp_line
			(start 0.67945 -0.3048)
			(end 0.67945 0.3048)
			(stroke
				(width 0.1)
				(type default)
			)
			(layer "F.Fab")
		)
		(fp_line
			(start 0.12065 -0.3048)
			(end 0.67945 -0.3048)
			(stroke
				(width 0.1)
				(type default)
			)
			(layer "F.Fab")
		)
		(fp_line
			(start 0.12065 -0.2794)
			(end 0.12065 -0.3048)
			(stroke
				(width 0.1)
				(type default)
			)
			(layer "F.Fab")
		)
		(fp_line
			(start -0.12065 -0.2794)
			(end 0.12065 -0.2794)
			(stroke
				(width 0.1)
				(type default)
			)
			(layer "F.Fab")
		)
		(fp_line
			(start 0.120396 0.2794)
			(end -0.12065 0.2794)
			(stroke
				(width 0.1)
				(type default)
			)
			(layer "F.Fab")
		)
		(fp_line
			(start -0.12065 0.2794)
			(end -0.12065 0.3048)
			(stroke
				(width 0.1)
				(type default)
			)
			(layer "F.Fab")
		)
		(fp_line
			(start 0.67945 0.3048)
			(end 0.120396 0.3048)
			(stroke
				(width 0.1)
				(type default)
			)
			(layer "F.Fab")
		)
		(fp_line
			(start 0.120396 0.3048)
			(end 0.120396 0.2794)
			(stroke
				(width 0.1)
				(type default)
			)
			(layer "F.Fab")
		)
		(fp_line
			(start -0.12065 0.3048)
			(end -0.67945 0.3048)
			(stroke
				(width 0.1)
				(type default)
			)
			(layer "F.Fab")
		)
		(fp_line
			(start -0.67945 0.3048)
			(end -0.67945 -0.305054)
			(stroke
				(width 0.1)
				(type default)
			)
			(layer "F.Fab")
		)
		(pad "1" smd circle
			(at -0.40005 0 90)
			(size 0 0)
			(layers "F.Cu" "F.Mask" "F.Paste")
			(net "CLK_100M_DB2000QL_PEX2_S1_R_DN")
		)
		(pad "2" smd circle
			(at 0.40005 0 90)
			(size 0 0)
			(layers "F.Cu" "F.Mask" "F.Paste")
			(net "CLK_100M_DB2000QL_PEX2_S1_DN")
		)
	)
)
